# BASEBOARD_FAB2 (Tioga Pass) — schematic netlist excerpt (pin names and nets, part order shuffled) for the footprints in the layout excerpt that follows; sources: Cadence DE-HDL packaged netlist, KiCad conversion of Wiwynn_Tioga_Pass_MB.brd

C3F1  CAP_A  47UF 4V 20% X5R  pkg 0603V  page 193 : A = P1V8_MCP_CPU1 ; B = GND
C1D19  CAP  1.0UF 16V 10% X6S  pkg 0402  page 199 : A = A_HSC_VCAP ; B = AGND_HSC
C4D18  CAP  220PF 50V 10% X7R  pkg 0402LF  page 201 : A = A_TSENSE_PVSA_CPU0 ; B = GND

(kicad_pcb
	(version 20260206)
	(generator "pcbnew")
	(generator_version "10.0")
	(general
		(thickness 1.6)
		(legacy_teardrops no)
	)
	(paper "A4")
	(title_block
		(title "Wiwynn_Tioga_Pass_MB.brd")
		(comment 1 "Tioga Pass / footprints 1788-1790 of 4770")
	)
	(layers
		(0 "F.Cu" signal "TOP")
		(4 "In1.Cu" signal "L2GND")
		(6 "In2.Cu" signal "L3")
		(8 "In3.Cu" signal "L4GND")
		(10 "In4.Cu" signal "L5")
		(12 "In5.Cu" signal "L6GND")
		(14 "In6.Cu" signal "L7VCC")
		(16 "In7.Cu" signal "L8VCC")
		(18 "In8.Cu" signal "L9GND")
		(20 "In9.Cu" signal "L10")
		(22 "In10.Cu" signal "L11GND")
		(24 "In11.Cu" signal "L12")
		(26 "In12.Cu" signal "L13GND")
		(2 "B.Cu" signal "BOTTOM")
		(9 "F.Adhes" user "F.Adhesive")
		(11 "B.Adhes" user "B.Adhesive")
		(13 "F.Paste" user "Package Geometry/Pastemask Top")
		(15 "B.Paste" user "Package Geometry/Pastemask Bottom")
		(5 "F.SilkS" user "Ref Des/Silkscreen Top")
		(7 "B.SilkS" user "Ref Des/Silkscreen Bottom")
		(1 "F.Mask" user "Board Geometry/Soldermask Top")
		(3 "B.Mask" user "Board Geometry/Soldermask Bottom")
		(17 "Dwgs.User" user "User.Drawings")
		(19 "Cmts.User" user "User.Comments")
		(21 "Eco1.User" user "User.Eco1")
		(23 "Eco2.User" user "User.Eco2")
		(25 "Edge.Cuts" user "Board Geometry/Outline")
		(27 "Margin" user)
		(31 "F.CrtYd" user "Package Geometry/Place Bound Top")
		(29 "B.CrtYd" user "Package Geometry/Place Bound Bottom")
		(35 "F.Fab" user "Ref Des/Assembly Top")
		(33 "B.Fab" user "Ref Des/Assembly Bottom")
	)
	(footprint ""
		(layer "F.Cu")
		(at 24.384 -73.9648)
		(property "Reference" "C1D19"
			(at 0 0 0)
			(layer "F.SilkS")
			(hide yes)
			(effects
				(font
					(size 1.27 1.27)
				)
			)
		)
		(property "Value" ""
			(at 0 0 0)
			(layer "F.Fab")
			(effects
				(font
					(size 1.27 1.27)
				)
			)
		)
		(duplicate_pad_numbers_are_jumpers no)
		(fp_poly
			(pts
				(xy 0.3048 -0.1016) (xy 0.3048 0.9906) (xy -0.3048 0.9906) (xy -0.3048 -0.1016)
			)
			(stroke
				(width 0)
				(type default)
			)
			(fill no)
			(layer "F.CrtYd")
		)
		(fp_line
			(start -0.3048 -0.1016)
			(end -0.3048 0.9906)
			(stroke
				(width 0.1)
				(type default)
			)
			(layer "F.Fab")
		)
		(fp_line
			(start -0.3048 0.9906)
			(end 0.3048 0.9906)
			(stroke
				(width 0.1)
				(type default)
			)
			(layer "F.Fab")
		)
		(fp_line
			(start 0.3048 -0.1016)
			(end -0.3048 -0.1016)
			(stroke
				(width 0.1)
				(type default)
			)
			(layer "F.Fab")
		)
		(fp_line
			(start 0.3048 0.9906)
			(end 0.3048 -0.1016)
			(stroke
				(width 0.1)
				(type default)
			)
			(layer "F.Fab")
		)
		(pad "1" smd rect
			(at 0 0)
			(size 0.508 0.508)
			(layers "F.Cu" "F.Mask" "F.Paste")
			(net "A_HSC_VCAP")
		)
		(pad "2" smd rect
			(at 0 0.889)
			(size 0.508 0.508)
			(layers "F.Cu" "F.Mask" "F.Paste")
			(net "AGND_HSC")
		)
		(zone
			(layer "F.Cu")
			(hatch none 0.5)
			(connect_pads
				(clearance 0)
			)
			(min_thickness 0.25)
			(keepout
				(tracks allowed)
				(vias not_allowed)
				(pads allowed)
				(copperpour not_allowed)
				(footprints allowed)
			)
			(placement
				(enabled no)
				(sheetname "")
			)
			(fill
				(thermal_gap 0.5)
				(thermal_bridge_width 0.5)
				(island_removal_mode 0)
			)
			(polygon
				(pts
					(xy 24.13 -73.7108) (xy 24.638 -73.7108) (xy 24.638 -73.3298) (xy 24.13 -73.3298)
				)
			)
		)
		(zone
			(layer "F.Cu")
			(hatch none 0.5)
			(connect_pads
				(clearance 0)
			)
			(min_thickness 0.25)
			(keepout
				(tracks not_allowed)
				(vias allowed)
				(pads allowed)
				(copperpour not_allowed)
				(footprints allowed)
			)
			(placement
				(enabled no)
				(sheetname "")
			)
			(fill
				(thermal_gap 0.5)
				(thermal_bridge_width 0.5)
				(island_removal_mode 0)
			)
			(polygon
				(pts
					(xy 24.13 -73.3298) (xy 24.638 -73.3298) (xy 24.638 -73.7108) (xy 24.13 -73.7108)
				)
			)
		)
	)
	(footprint ""
		(layer "F.Cu")
		(at 163.277042 -34.671)
		(property "Reference" "C3F1"
			(at 0 0 0)
			(layer "F.SilkS")
			(hide yes)
			(effects
				(font
					(size 1.27 1.27)
				)
			)
		)
		(property "Value" ""
			(at 0 0 0)
			(layer "F.Fab")
			(effects
				(font
					(size 1.27 1.27)
				)
			)
		)
		(duplicate_pad_numbers_are_jumpers no)
		(fp_rect
			(start -0.500126 1.598422)
			(end 0.500126 -0.201422)
			(stroke
				(width 0)
				(type default)
			)
			(fill no)
			(layer "F.CrtYd")
		)
		(fp_line
			(start -0.500126 -0.201422)
			(end 0.500126 -0.201422)
			(stroke
				(width 0.1)
				(type default)
			)
			(layer "F.Fab")
		)
		(fp_line
			(start -0.500126 1.598422)
			(end -0.500126 -0.201422)
			(stroke
				(width 0.1)
				(type default)
			)
			(layer "F.Fab")
		)
		(fp_line
			(start 0.500126 -0.201422)
			(end 0.500126 1.598422)
			(stroke
				(width 0.1)
				(type default)
			)
			(layer "F.Fab")
		)
		(fp_line
			(start 0.500126 1.598422)
			(end -0.500126 1.598422)
			(stroke
				(width 0.1)
				(type default)
			)
			(layer "F.Fab")
		)
		(pad "1" smd rect
			(at 0 0 270)
			(size 0.889 0.9906)
			(layers "F.Cu" "F.Mask" "F.Paste")
			(net "P1V8_MCP_CPU1")
		)
		(pad "2" smd rect
			(at 0 1.397 270)
			(size 0.889 0.9906)
			(layers "F.Cu" "F.Mask" "F.Paste")
			(net "GND")
		)
		(zone
			(layer "F.Cu")
			(hatch none 0.5)
			(connect_pads
				(clearance 0)
			)
			(min_thickness 0.25)
			(keepout
				(tracks not_allowed)
				(vias allowed)
				(pads allowed)
				(copperpour not_allowed)
				(footprints allowed)
			)
			(placement
				(enabled no)
				(sheetname "")
			)
			(fill
				(thermal_gap 0.5)
				(thermal_bridge_width 0.5)
				(island_removal_mode 0)
			)
			(polygon
				(pts
					(xy 162.781742 -33.7185) (xy 163.772342 -33.7185) (xy 163.772342 -34.2265) (xy 162.781742 -34.2265)
				)
			)
		)
		(zone
			(layer "F.Cu")
			(hatch none 0.5)
			(connect_pads
				(clearance 0)
			)
			(min_thickness 0.25)
			(keepout
				(tracks allowed)
				(vias not_allowed)
				(pads allowed)
				(copperpour not_allowed)
				(footprints allowed)
			)
			(placement
				(enabled no)
				(sheetname "")
			)
			(fill
				(thermal_gap 0.5)
				(thermal_bridge_width 0.5)
				(island_removal_mode 0)
			)
			(polygon
				(pts
					(xy 162.781742 -33.7185) (xy 163.772342 -33.7185) (xy 163.772342 -34.2265) (xy 162.781742 -34.2265)
				)
			)
		)
	)
	(footprint ""
		(layer "F.Cu")
		(at 185.1406 -75.4253 180)
		(property "Reference" "C4D18"
			(at 0 0 180)
			(layer "F.SilkS")
			(hide yes)
			(effects
				(font
					(size 1.27 1.27)
				)
			)
		)
		(property "Value" ""
			(at 0 0 180)
			(layer "F.Fab")
			(effects
				(font
					(size 1.27 1.27)
				)
			)
		)
		(duplicate_pad_numbers_are_jumpers no)
		(fp_rect
			(start 0.3048 -0.1016)
			(end -0.3048 0.9906)
			(stroke
				(width 0)
				(type default)
			)
			(fill no)
			(layer "F.CrtYd")
		)
		(fp_line
			(start 0.3048 0.9906)
			(end 0.3048 -0.1016)
			(stroke
				(width 0.1)
				(type default)
			)
			(layer "F.Fab")
		)
		(fp_line
			(start 0.3048 -0.1016)
			(end -0.3048 -0.1016)
			(stroke
				(width 0.1)
				(type default)
			)
			(layer "F.Fab")
		)
		(fp_line
			(start -0.3048 0.9906)
			(end 0.3048 0.9906)
			(stroke
				(width 0.1)
				(type default)
			)
			(layer "F.Fab")
		)
		(fp_line
			(start -0.3048 -0.1016)
			(end -0.3048 0.9906)
			(stroke
				(width 0.1)
				(type default)
			)
			(layer "F.Fab")
		)
		(pad "1" smd rect
			(at 0 0 180)
			(size 0.508 0.508)
			(layers "F.Cu" "F.Mask" "F.Paste")
			(net "A_TSENSE_PVSA_CPU0")
		)
		(pad "2" smd rect
			(at 0 0.889 180)
			(size 0.508 0.508)
			(layers "F.Cu" "F.Mask" "F.Paste")
			(net "GND")
		)
		(zone
			(layer "F.Cu")
			(hatch none 0.5)
			(connect_pads
				(clearance 0)
			)
			(min_thickness 0.25)
			(keepout
				(tracks allowed)
				(vias not_allowed)
				(pads allowed)
				(copperpour not_allowed)
				(footprints allowed)
			)
			(placement
				(enabled no)
				(sheetname "")
			)
			(fill
				(thermal_gap 0.5)
				(thermal_bridge_width 0.5)
				(island_removal_mode 0)
			)
			(polygon
				(pts
					(xy 184.8866 -75.6793) (xy 185.3946 -75.6793) (xy 185.3946 -76.0603) (xy 184.8866 -76.0603)
				)
			)
		)
		(zone
			(layer "F.Cu")
			(hatch none 0.5)
			(connect_pads
				(clearance 0)
			)
			(min_thickness 0.25)
			(keepout
				(tracks not_allowed)
				(vias allowed)
				(pads allowed)
				(copperpour not_allowed)
				(footprints allowed)
			)
			(placement
				(enabled no)
				(sheetname "")
			)
			(fill
				(thermal_gap 0.5)
				(thermal_bridge_width 0.5)
				(island_removal_mode 0)
			)
			(polygon
				(pts
					(xy 184.8866 -75.6793) (xy 185.3946 -75.6793) (xy 185.3946 -76.0603) (xy 184.8866 -76.0603)
				)
			)
		)
	)
)
